# T6G (Grand Teton) — schematic netlist excerpt (pin names and nets, part order shuffled) for the footprints in the layout excerpt that follows; sources: Cadence DE-HDL packaged netlist, KiCad conversion of 04192023_DAF0TMB3IC0_F0TG_MB_C_brd_V02_OCP.brd

J27  SCONN288_DDR506112002KQ  IO  pkg DDR288S_1-1VXC  page 105
  VIN_BULK0  = P12V_MEM_CPU1
  RFU0  = NC
  VIN_MGMT  = P3V3_AUX
  HSCL  = I3C_SPD_DDRH_CPU1_SCL
  HSDA  = I3C_SPD_DDRH_CPU1_SDA
  VSS0  = GND
  DQ0_A  = M_H_CPU1_SA_DQ<0>
  VSS1  = GND
  DQ1_A  = M_H_CPU1_SA_DQ<1>
  VSS2  = GND
  DQS0_A_T  = M_H_CPU1_SA_DQS_DP<0>
  DQS0_A_C  = M_H_CPU1_SA_DQS_DN<0>
  VSS3  = GND
  DQ4_A  = M_H_CPU1_SA_DQ<4>
  VSS4  = GND
  DQ5_A  = M_H_CPU1_SA_DQ<5>
  VSS5  = GND
  DQ8_A  = M_H_CPU1_SA_DQ<8>
  VSS6  = GND
  DQ9_A  = M_H_CPU1_SA_DQ<9>
  VSS7  = GND
  DQS1_A_T  = M_H_CPU1_SA_DQS_DP<1>
  DQS1_A_C  = M_H_CPU1_SA_DQS_DN<1>
  VSS8  = GND
  DQ12_A  = M_H_CPU1_SA_DQ<12>
  VSS9  = GND
  DQ13_A  = M_H_CPU1_SA_DQ<13>
  VSS10  = GND
  DQ16_A  = M_H_CPU1_SA_DQ<16>
  VSS11  = GND
  DQ17_A  = M_H_CPU1_SA_DQ<17>
  VSS12  = GND
  DQS2_A_T  = M_H_CPU1_SA_DQS_DP<2>
  DQS2_A_C  = M_H_CPU1_SA_DQS_DN<2>
  VSS13  = GND
  DQ20_A  = M_H_CPU1_SA_DQ<20>
  VSS14  = GND
  DQ21_A  = M_H_CPU1_SA_DQ<21>
  VSS15  = GND
  DQ24_A  = M_H_CPU1_SA_DQ<24>
  VSS16  = GND
  DQ25_A  = M_H_CPU1_SA_DQ<25>
  VSS17  = GND
  DQS3_A_T  = M_H_CPU1_SA_DQS_DP<3>
  DQS3_A_C  = M_H_CPU1_SA_DQS_DN<3>
  VSS18  = GND
  DQ28_A  = M_H_CPU1_SA_DQ<28>
  VSS19  = GND
  DQ29_A  = M_H_CPU1_SA_DQ<29>
  VSS20  = GND
  CB0_A  = M_H_CPU1_SA_CB<0>
  VSS21  = GND
  CB1_A  = M_H_CPU1_SA_CB<1>
  VSS22  = GND
  DQS4_A_T  = M_H_CPU1_SA_DQS_DP<4>
  DQS4_A_C  = M_H_CPU1_SA_DQS_DN<4>
  VSS23  = GND
  CB4_A  = M_H_CPU1_SA_CB<4>
  VSS24  = GND
  CB5_A  = M_H_CPU1_SA_CB<5>
  VSS25  = GND
  ALERT_N  = M_H_CPU1_ALERT_N
  VSS26  = GND
  CS0_A_N  = M_H_CPU1_SA_CS_N<0>
  VSS27  = GND
  CA0_A  = M_H_CPU1_SA_CA<0>
  VSS28  = GND
  CA2_A  = M_H_CPU1_SA_CA<2>
  VSS29  = GND
  CA4_A  = M_H_CPU1_SA_CA<4>
  VSS30  = GND
  CA6_A  = M_H_CPU1_SA_CA<6>
  VSS31  = GND
  PAR_A  = M_H_CPU1_SA_PAR
  VSS32  = GND
  CA0_B  = M_H_CPU1_SB_CA<0>
  VSS33  = GND
  CA2_B  = M_H_CPU1_SB_CA<2>
  VSS34  = GND
  CA4_B  = M_H_CPU1_SB_CA<4>
  VSS35  = GND
  CA6_B  = M_H_CPU1_SB_CA<6>
  VSS36  = GND
  CS0_B_N  = M_H_CPU1_SB_CS_N<0>
  VSS37  = GND
  \lbd||rsp_a_n\  = M_H_CPU1_SA_RSP<0>
  \lbs||rsp_b_n\  = M_H_CPU1_SB_RSP<0>
  VSS38  = GND
  CB4_B  = M_H_CPU1_SB_CB<4>
  VSS39  = GND
  CB5_B  = M_H_CPU1_SB_CB<5>
  VSS40  = GND
  \dqs9_b_t||tdqs9_b_t||dbi4_b_n\  = M_H_CPU1_SB_DQS_DP<9>
  \dqs9_b_c||tdqs9_b_c\  = M_H_CPU1_SB_DQS_DN<9>
  VSS41  = GND
  CB0_B  = M_H_CPU1_SB_CB<0>
  VSS42  = GND
  CB1_B  = M_H_CPU1_SB_CB<1>
  VSS43  = GND
  DQ0_B  = M_H_CPU1_SB_DQ<0>
  VSS44  = GND
  DQ1_B  = M_H_CPU1_SB_DQ<1>
  VSS45  = GND
  DQS0_B_T  = M_H_CPU1_SB_DQS_DP<0>
  DQS0_B_C  = M_H_CPU1_SB_DQS_DN<0>
  VSS46  = GND
  DQ4_B  = M_H_CPU1_SB_DQ<4>
  VSS47  = GND
  DQ5_B  = M_H_CPU1_SB_DQ<5>
  VSS48  = GND
  DQ8_B  = M_H_CPU1_SB_DQ<8>
  VSS49  = GND
  DQ9_B  = M_H_CPU1_SB_DQ<9>
  VSS50  = GND
  DQS1_B_T  = M_H_CPU1_SB_DQS_DP<1>
  DQS1_B_C  = M_H_CPU1_SB_DQS_DN<1>
  VSS51  = GND
  DQ12_B  = M_H_CPU1_SB_DQ<12>
  VSS52  = GND
  DQ13_B  = M_H_CPU1_SB_DQ<13>
  VSS53  = GND
  DQ16_B  = M_H_CPU1_SB_DQ<16>
  VSS54  = GND
  DQ17_B  = M_H_CPU1_SB_DQ<17>
  VSS55  = GND
  DQS2_B_T  = M_H_CPU1_SB_DQS_DP<2>
  DQS2_B_C  = M_H_CPU1_SB_DQS_DN<2>
  VSS56  = GND
  DQ20_B  = M_H_CPU1_SB_DQ<20>
  VSS57  = GND
  DQ21_B  = M_H_CPU1_SB_DQ<21>
  VSS58  = GND
  DQ24_B  = M_H_CPU1_SB_DQ<24>
  VSS59  = GND
  DQ25_B  = M_H_CPU1_SB_DQ<25>
  VSS60  = GND
  DQS3_B_T  = M_H_CPU1_SB_DQS_DP<3>
  DQS3_B_C  = M_H_CPU1_SB_DQS_DN<3>
  VSS61  = GND
  DQ28_B  = M_H_CPU1_SB_DQ<28>
  VSS62  = GND
  DQ29_B  = M_H_CPU1_SB_DQ<29>
  VSS63  = GND
  RFU1  = NC
  VIN_BULK1  = P12V_MEM_CPU1
  VIN_BULK2  = P12V_MEM_CPU1
  \pwr_good||fail_n\  = PWRGD_CHH_CPU1_DIMM
  HAS  = PD_CHH_CPU1_DIMM_SAA
  RFU2  = NC
  RFU3  = NC
  VSS64  = GND
  DQ2_A  = M_H_CPU1_SA_DQ<2>
  VSS65  = GND
  DQ3_A  = M_H_CPU1_SA_DQ<3>
  VSS66  = GND
  \dqs5_a_c||tdqs5_a_c||dqs5_a_t||tdqs5_a_t\  = M_H_CPU1_SA_DQS_DN<5>
  \dqs5_a_t||tdqs5_a_t\  = M_H_CPU1_SA_DQS_DP<5>
  VSS67  = GND
  DQ6_A  = M_H_CPU1_SA_DQ<6>
  VSS68  = GND
  DQ7_A  = M_H_CPU1_SA_DQ<7>
  VSS69  = GND
  DQ10_A  = M_H_CPU1_SA_DQ<10>
  VSS70  = GND
  DQ11_A  = M_H_CPU1_SA_DQ<11>
  VSS71  = GND
  \dqs6_a_c||tdqs6_a_c||dqs6_a_t||tdqs6_a_t\  = M_H_CPU1_SA_DQS_DN<6>
  \dqs6_a_t||tdqs6_a_t\  = M_H_CPU1_SA_DQS_DP<6>
  VSS72  = GND
  DQ14_A  = M_H_CPU1_SA_DQ<14>
  VSS73  = GND
  DQ15_A  = M_H_CPU1_SA_DQ<15>
  VSS74  = GND
  DQ18_A  = M_H_CPU1_SA_DQ<18>
  VSS75  = GND
  DQ19_A  = M_H_CPU1_SA_DQ<19>
  VSS76  = GND
  \dqs7_a_c||tdqs7_a_c\  = M_H_CPU1_SA_DQS_DN<7>
  \dqs7_a_t||tdqs7_a_t\  = M_H_CPU1_SA_DQS_DP<7>
  VSS77  = GND
  DQ22_A  = M_H_CPU1_SA_DQ<22>
  VSS78  = GND
  DQ23_A  = M_H_CPU1_SA_DQ<23>
  VSS79  = GND
  DQ26_A  = M_H_CPU1_SA_DQ<26>
  VSS80  = GND
  DQ27_A  = M_H_CPU1_SA_DQ<27>
  VSS81  = GND
  \dqs8_a_c||tdqs8_a_c\  = M_H_CPU1_SA_DQS_DN<8>
  \dqs8_a_t||tdqs8_a_t\  = M_H_CPU1_SA_DQS_DP<8>
  VSS82  = GND
  DQ30_A  = M_H_CPU1_SA_DQ<30>
  VSS83  = GND
  DQ31_A  = M_H_CPU1_SA_DQ<31>
  VSS84  = GND
  CB2_A  = M_H_CPU1_SA_CB<2>
  VSS85  = GND
  CB3_A  = M_H_CPU1_SA_CB<3>
  VSS86  = GND
  \dqs9_a_c||tdqs9_a_c\  = M_H_CPU1_SA_DQS_DN<9>
  \dqs9_a_t||tdqs9_a_t\  = M_H_CPU1_SA_DQS_DP<9>
  VSS87  = GND
  CB6_A  = M_H_CPU1_SA_CB<6>
  VSS88  = GND
  CB7_A  = M_H_CPU1_SA_CB<7>
  VSS89  = GND
  RESET_N  = M_H_CPU1_RESET_N
  VSS90  = GND
  CS1_A_N  = M_H_CPU1_SA_CS_N<1>
  VSS91  = GND
  CA1_A  = M_H_CPU1_SA_CA<1>
  VSS92  = GND
  CA3_A  = M_H_CPU1_SA_CA<3>
  VSS93  = GND
  CA5_A  = M_H_CPU1_SA_CA<5>
  VSS94  = GND
  CK_T  = M_H_CPU1_CLK_DP<0>
  CK_C  = M_H_CPU1_CLK_DN<0>
  VSS95  = GND
  RFU4  = NC
  CA1_B  = M_H_CPU1_SB_CA<1>
  VSS96  = GND
  CA3_B  = M_H_CPU1_SB_CA<3>
  VSS97  = GND
  CA5_B  = M_H_CPU1_SB_CA<5>
  VSS98  = GND
  PAR_B  = M_H_CPU1_SB_PAR
  VSS99  = GND
  CS1_B_N  = M_H_CPU1_SB_CS_N<1>
  VSS100  = GND
  RFU5  = NC
  RFU6  = NC
  VSS101  = GND
  CB6_B  = M_H_CPU1_SB_CB<6>
  VSS102  = GND
  CB7_B  = M_H_CPU1_SB_CB<7>
  VSS103  = GND
  DQS4_B_C  = M_H_CPU1_SB_DQS_DN<4>
  DQS4_B_T  = M_H_CPU1_SB_DQS_DP<4>
  VSS104  = GND
  CB2_B  = M_H_CPU1_SB_CB<2>
  VSS105  = GND
  CB3_B  = M_H_CPU1_SB_CB<3>
  VSS106  = GND
  DQ2_B  = M_H_CPU1_SB_DQ<2>
  VSS107  = GND
  DQ3_B  = M_H_CPU1_SB_DQ<3>
  VSS108  = GND
  \dqs5_b_c||tdqs5_b_c\  = M_H_CPU1_SB_DQS_DN<5>
  \dqs5_b_t||tdqs5_b_t\  = M_H_CPU1_SB_DQS_DP<5>
  VSS109  = GND
  DQ6_B  = M_H_CPU1_SB_DQ<6>
  VSS110  = GND
  DQ7_B  = M_H_CPU1_SB_DQ<7>
  VSS111  = GND
  DQ10_B  = M_H_CPU1_SB_DQ<10>
  VSS112  = GND
  DQ11_B  = M_H_CPU1_SB_DQ<11>
  VSS113  = GND
  \dqs6_b_c||tdqs6_b_c\  = M_H_CPU1_SB_DQS_DN<6>
  \dqs6_b_t||tdqs6_b_t\  = M_H_CPU1_SB_DQS_DP<6>
  VSS114  = GND
  DQ14_B  = M_H_CPU1_SB_DQ<14>
  VSS115  = GND
  DQ15_B  = M_H_CPU1_SB_DQ<15>
  VSS116  = GND
  DQ18_B  = M_H_CPU1_SB_DQ<18>
  VSS117  = GND
  DQ19_B  = M_H_CPU1_SB_DQ<19>
  VSS118  = GND
  \dqs7_b_c||tdqs7_b_c\  = M_H_CPU1_SB_DQS_DN<7>
  \dqs7_b_t||tdqs7_b_t\  = M_H_CPU1_SB_DQS_DP<7>
  VSS119  = GND
  DQ22_B  = M_H_CPU1_SB_DQ<22>
  VSS120  = GND
  DQ23_B  = M_H_CPU1_SB_DQ<23>
  VSS121  = GND
  DQ26_B  = M_H_CPU1_SB_DQ<26>
  VSS122  = GND
  DQ27_B  = M_H_CPU1_SB_DQ<27>
  VSS123  = GND
  \dqs8_b_c||tdqs8_b_c\  = M_H_CPU1_SB_DQS_DN<8>
  \dqs8_b_t||tdqs8_b_t\  = M_H_CPU1_SB_DQS_DP<8>
  VSS124  = GND
  DQ30_B  = M_H_CPU1_SB_DQ<30>
  VSS125  = GND
  DQ31_B  = M_H_CPU1_SB_DQ<31>
  VSS126  = GND
  G1  = GND
  G2  = GND
  G3  = GND

(kicad_pcb
	(version 20260206)
	(generator "pcbnew")
	(generator_version "10.0")
	(general
		(thickness 1.6)
		(legacy_teardrops no)
	)
	(paper "A4")
	(title_block
		(title "04192023_DAF0TMB3IC0_F0TG_MB_C_brd_V02_OCP.brd")
		(comment 1 "Grand Teton / footprint 583 of 8354 (J27), pads 47-92 of 291")
	)
	(layers
		(0 "F.Cu" signal "TOP")
		(4 "In1.Cu" signal "GND")
		(6 "In2.Cu" signal "IN1")
		(8 "In3.Cu" signal "GND1")
		(10 "In4.Cu" signal "IN2")
		(12 "In5.Cu" signal "GND2")
		(14 "In6.Cu" signal "IN3")
		(16 "In7.Cu" signal "GND3")
		(18 "In8.Cu" signal "VCC")
		(20 "In9.Cu" signal "VCC1")
		(22 "In10.Cu" signal "GND4")
		(24 "In11.Cu" signal "IN4")
		(26 "In12.Cu" signal "GND5")
		(28 "In13.Cu" signal "IN5")
		(30 "In14.Cu" signal "GND6")
		(32 "In15.Cu" signal "IN6")
		(34 "In16.Cu" signal "GND7")
		(2 "B.Cu" signal "BOTTOM")
		(9 "F.Adhes" user "F.Adhesive")
		(11 "B.Adhes" user "B.Adhesive")
		(13 "F.Paste" user "Package Geometry/Pastemask Top")
		(15 "B.Paste" user "Package Geometry/Pastemask Bottom")
		(5 "F.SilkS" user "Ref Des/Silkscreen Top")
		(7 "B.SilkS" user "Ref Des/Silkscreen Bottom")
		(1 "F.Mask" user "Board Geometry/Soldermask Top")
		(3 "B.Mask" user "Board Geometry/Soldermask Bottom")
		(17 "Dwgs.User" user "User.Drawings")
		(19 "Cmts.User" user "User.Comments")
		(21 "Eco1.User" user "User.Eco1")
		(23 "Eco2.User" user "User.Eco2")
		(25 "Edge.Cuts" user "Board Geometry/Outline")
		(27 "Margin" user)
		(31 "F.CrtYd" user "Package Geometry/Place Bound Top")
		(29 "B.CrtYd" user "Package Geometry/Place Bound Bottom")
		(35 "F.Fab" user "Ref Des/Assembly Top")
		(33 "B.Fab" user "Ref Des/Assembly Bottom")
	)
	(footprint ""
		(layer "F.Cu")
		(at 174.022004 -255.560322 180)
		(property "Reference" "J27"
			(at -2.7178 -81.857088 0)
			(unlocked yes)
			(layer "F.SilkS")
			(effects
				(font
					(size 0.7874 0.5842)
					(thickness 0.1524)
				)
			)
		)
		(property "Value" ""
			(at 0 0 180)
			(layer "F.Fab")
			(effects
				(font
					(size 1.27 1.27)
				)
			)
		)
		(duplicate_pad_numbers_are_jumpers no)
		(pad "47" smd rect
			(at -2.050034 -24.224996 90)
			(size 0.519938 1.4986)
			(layers "F.Cu" "F.Mask" "F.Paste")
			(net "M_H_CPU1_SA_DQ<28>")
		)
		(pad "48" smd rect
			(at -2.050034 -23.375112 90)
			(size 0.519938 1.4986)
			(layers "F.Cu" "F.Mask" "F.Paste")
			(net "GND")
		)
		(pad "49" smd rect
			(at -2.050034 -22.524974 90)
			(size 0.519938 1.4986)
			(layers "F.Cu" "F.Mask" "F.Paste")
			(net "M_H_CPU1_SA_DQ<29>")
		)
		(pad "50" smd rect
			(at -2.050034 -21.67509 90)
			(size 0.519938 1.4986)
			(layers "F.Cu" "F.Mask" "F.Paste")
			(net "GND")
		)
		(pad "51" smd rect
			(at -2.050034 -20.824952 90)
			(size 0.519938 1.4986)
			(layers "F.Cu" "F.Mask" "F.Paste")
			(net "M_H_CPU1_SA_CB<0>")
		)
		(pad "52" smd rect
			(at -2.050034 -19.975068 90)
			(size 0.519938 1.4986)
			(layers "F.Cu" "F.Mask" "F.Paste")
			(net "GND")
		)
		(pad "53" smd rect
			(at -2.050034 -19.12493 90)
			(size 0.519938 1.4986)
			(layers "F.Cu" "F.Mask" "F.Paste")
			(net "M_H_CPU1_SA_CB<1>")
		)
		(pad "54" smd rect
			(at -2.050034 -18.275046 90)
			(size 0.519938 1.4986)
			(layers "F.Cu" "F.Mask" "F.Paste")
			(net "GND")
		)
		(pad "55" smd rect
			(at -2.050034 -17.424908 90)
			(size 0.519938 1.4986)
			(layers "F.Cu" "F.Mask" "F.Paste")
			(net "M_H_CPU1_SA_DQS_DP<4>")
		)
		(pad "56" smd rect
			(at -2.050034 -16.575024 90)
			(size 0.519938 1.4986)
			(layers "F.Cu" "F.Mask" "F.Paste")
			(net "M_H_CPU1_SA_DQS_DN<4>")
		)
		(pad "57" smd rect
			(at -2.050034 -15.724886 90)
			(size 0.519938 1.4986)
			(layers "F.Cu" "F.Mask" "F.Paste")
			(net "GND")
		)
		(pad "58" smd rect
			(at -2.050034 -14.875002 90)
			(size 0.519938 1.4986)
			(layers "F.Cu" "F.Mask" "F.Paste")
			(net "M_H_CPU1_SA_CB<4>")
		)
		(pad "59" smd rect
			(at -2.050034 -14.025118 90)
			(size 0.519938 1.4986)
			(layers "F.Cu" "F.Mask" "F.Paste")
			(net "GND")
		)
		(pad "60" smd rect
			(at -2.050034 -13.17498 90)
			(size 0.519938 1.4986)
			(layers "F.Cu" "F.Mask" "F.Paste")
			(net "M_H_CPU1_SA_CB<5>")
		)
		(pad "61" smd rect
			(at -2.050034 -12.325096 90)
			(size 0.519938 1.4986)
			(layers "F.Cu" "F.Mask" "F.Paste")
			(net "GND")
		)
		(pad "62" smd rect
			(at -2.050034 -11.474958 90)
			(size 0.519938 1.4986)
			(layers "F.Cu" "F.Mask" "F.Paste")
			(net "M_H_CPU1_ALERT_N")
		)
		(pad "63" smd rect
			(at -2.050034 -10.625074 90)
			(size 0.519938 1.4986)
			(layers "F.Cu" "F.Mask" "F.Paste")
			(net "GND")
		)
		(pad "64" smd rect
			(at -2.050034 -9.774936 90)
			(size 0.519938 1.4986)
			(layers "F.Cu" "F.Mask" "F.Paste")
			(net "M_H_CPU1_SA_CS_N<0>")
		)
		(pad "65" smd rect
			(at -2.050034 -8.925052 90)
			(size 0.519938 1.4986)
			(layers "F.Cu" "F.Mask" "F.Paste")
			(net "GND")
		)
		(pad "66" smd rect
			(at -2.050034 -8.074914 90)
			(size 0.519938 1.4986)
			(layers "F.Cu" "F.Mask" "F.Paste")
			(net "M_H_CPU1_SA_CA<0>")
		)
		(pad "67" smd rect
			(at -2.050034 -7.22503 90)
			(size 0.519938 1.4986)
			(layers "F.Cu" "F.Mask" "F.Paste")
			(net "GND")
		)
		(pad "68" smd rect
			(at -2.050034 -6.374892 90)
			(size 0.519938 1.4986)
			(layers "F.Cu" "F.Mask" "F.Paste")
			(net "M_H_CPU1_SA_CA<2>")
		)
		(pad "69" smd rect
			(at -2.050034 -5.525008 90)
			(size 0.519938 1.4986)
			(layers "F.Cu" "F.Mask" "F.Paste")
			(net "GND")
		)
		(pad "70" smd rect
			(at -2.050034 -4.675124 90)
			(size 0.519938 1.4986)
			(layers "F.Cu" "F.Mask" "F.Paste")
			(net "M_H_CPU1_SA_CA<4>")
		)
		(pad "71" smd rect
			(at -2.050034 -3.824986 90)
			(size 0.519938 1.4986)
			(layers "F.Cu" "F.Mask" "F.Paste")
			(net "GND")
		)
		(pad "72" smd rect
			(at -2.050034 -2.975102 90)
			(size 0.519938 1.4986)
			(layers "F.Cu" "F.Mask" "F.Paste")
			(net "M_H_CPU1_SA_CA<6>")
		)
		(pad "73" smd rect
			(at -2.050034 -2.124964 90)
			(size 0.519938 1.4986)
			(layers "F.Cu" "F.Mask" "F.Paste")
			(net "GND")
		)
		(pad "74" smd rect
			(at -2.050034 -1.27508 90)
			(size 0.519938 1.4986)
			(layers "F.Cu" "F.Mask" "F.Paste")
			(net "M_H_CPU1_SA_PAR")
		)
		(pad "75" smd rect
			(at -2.050034 -0.424942 90)
			(size 0.519938 1.4986)
			(layers "F.Cu" "F.Mask" "F.Paste")
			(net "GND")
		)
		(pad "76" smd rect
			(at -2.050034 5.525008 90)
			(size 0.519938 1.4986)
			(layers "F.Cu" "F.Mask" "F.Paste")
			(net "M_H_CPU1_SB_CA<0>")
		)
		(pad "77" smd rect
			(at -2.050034 6.374892 90)
			(size 0.519938 1.4986)
			(layers "F.Cu" "F.Mask" "F.Paste")
			(net "GND")
		)
		(pad "78" smd rect
			(at -2.050034 7.22503 90)
			(size 0.519938 1.4986)
			(layers "F.Cu" "F.Mask" "F.Paste")
			(net "M_H_CPU1_SB_CA<2>")
		)
		(pad "79" smd rect
			(at -2.050034 8.074914 90)
			(size 0.519938 1.4986)
			(layers "F.Cu" "F.Mask" "F.Paste")
			(net "GND")
		)
		(pad "80" smd rect
			(at -2.050034 8.925052 90)
			(size 0.519938 1.4986)
			(layers "F.Cu" "F.Mask" "F.Paste")
			(net "M_H_CPU1_SB_CA<4>")
		)
		(pad "81" smd rect
			(at -2.050034 9.774936 90)
			(size 0.519938 1.4986)
			(layers "F.Cu" "F.Mask" "F.Paste")
			(net "GND")
		)
		(pad "82" smd rect
			(at -2.050034 10.625074 90)
			(size 0.519938 1.4986)
			(layers "F.Cu" "F.Mask" "F.Paste")
			(net "M_H_CPU1_SB_CA<6>")
		)
		(pad "83" smd rect
			(at -2.050034 11.474958 90)
			(size 0.519938 1.4986)
			(layers "F.Cu" "F.Mask" "F.Paste")
			(net "GND")
		)
		(pad "84" smd rect
			(at -2.050034 12.325096 90)
			(size 0.519938 1.4986)
			(layers "F.Cu" "F.Mask" "F.Paste")
			(net "M_H_CPU1_SB_CS_N<0>")
		)
		(pad "85" smd rect
			(at -2.050034 13.17498 90)
			(size 0.519938 1.4986)
			(layers "F.Cu" "F.Mask" "F.Paste")
			(net "GND")
		)
		(pad "86" smd rect
			(at -2.050034 14.025118 90)
			(size 0.519938 1.4986)
			(layers "F.Cu" "F.Mask" "F.Paste")
			(net "M_H_CPU1_SA_RSP<0>")
		)
		(pad "87" smd rect
			(at -2.050034 14.875002 90)
			(size 0.519938 1.4986)
			(layers "F.Cu" "F.Mask" "F.Paste")
			(net "M_H_CPU1_SB_RSP<0>")
		)
		(pad "88" smd rect
			(at -2.050034 15.724886 90)
			(size 0.519938 1.4986)
			(layers "F.Cu" "F.Mask" "F.Paste")
			(net "GND")
		)
		(pad "89" smd rect
			(at -2.050034 16.575024 90)
			(size 0.519938 1.4986)
			(layers "F.Cu" "F.Mask" "F.Paste")
			(net "M_H_CPU1_SB_CB<4>")
		)
		(pad "90" smd rect
			(at -2.050034 17.424908 90)
			(size 0.519938 1.4986)
			(layers "F.Cu" "F.Mask" "F.Paste")
			(net "GND")
		)
		(pad "91" smd rect
			(at -2.050034 18.275046 90)
			(size 0.519938 1.4986)
			(layers "F.Cu" "F.Mask" "F.Paste")
			(net "M_H_CPU1_SB_CB<5>")
		)
		(pad "92" smd rect
			(at -2.050034 19.12493 90)
			(size 0.519938 1.4986)
			(layers "F.Cu" "F.Mask" "F.Paste")
			(net "GND")
		)
	)
)
